# BASEBOARD_FAB2 (Tioga Pass) — schematic netlist excerpt (pin names and nets, part order shuffled) for the footprints in the layout excerpt that follows; sources: Cadence DE-HDL packaged netlist, KiCad conversion of Wiwynn_Tioga_Pass_MB.brd

R25W164  RES  49.9 1% CHIP  pkg 0402  page 255 : A = P1V05_PCH_STBY ; B = P0V7_GTL2014_VREF_6
R8E18  RES  1.0K 0.1% CHIP  pkg 0402  page 241 : A = P5V_STBY ; B = GND
R25W150  RES  4.75K 1% CHIP  pkg 0402  page 150 : A = GND ; B = RMII_BMC_PCH_SPRNGVLLE_TXD0_R

(kicad_pcb
	(version 20260206)
	(generator "pcbnew")
	(generator_version "10.0")
	(general
		(thickness 1.6)
		(legacy_teardrops no)
	)
	(paper "A4")
	(title_block
		(title "Wiwynn_Tioga_Pass_MB.brd")
		(comment 1 "Tioga Pass / footprints 2301-2303 of 4770")
	)
	(layers
		(0 "F.Cu" signal "TOP")
		(4 "In1.Cu" signal "L2GND")
		(6 "In2.Cu" signal "L3")
		(8 "In3.Cu" signal "L4GND")
		(10 "In4.Cu" signal "L5")
		(12 "In5.Cu" signal "L6GND")
		(14 "In6.Cu" signal "L7VCC")
		(16 "In7.Cu" signal "L8VCC")
		(18 "In8.Cu" signal "L9GND")
		(20 "In9.Cu" signal "L10")
		(22 "In10.Cu" signal "L11GND")
		(24 "In11.Cu" signal "L12")
		(26 "In12.Cu" signal "L13GND")
		(2 "B.Cu" signal "BOTTOM")
		(9 "F.Adhes" user "F.Adhesive")
		(11 "B.Adhes" user "B.Adhesive")
		(13 "F.Paste" user "Package Geometry/Pastemask Top")
		(15 "B.Paste" user "Package Geometry/Pastemask Bottom")
		(5 "F.SilkS" user "Ref Des/Silkscreen Top")
		(7 "B.SilkS" user "Ref Des/Silkscreen Bottom")
		(1 "F.Mask" user "Board Geometry/Soldermask Top")
		(3 "B.Mask" user "Board Geometry/Soldermask Bottom")
		(17 "Dwgs.User" user "User.Drawings")
		(19 "Cmts.User" user "User.Comments")
		(21 "Eco1.User" user "User.Eco1")
		(23 "Eco2.User" user "User.Eco2")
		(25 "Edge.Cuts" user "Board Geometry/Outline")
		(27 "Margin" user)
		(31 "F.CrtYd" user "Package Geometry/Place Bound Top")
		(29 "B.CrtYd" user "Package Geometry/Place Bound Bottom")
		(35 "F.Fab" user "Ref Des/Assembly Top")
		(33 "B.Fab" user "Ref Des/Assembly Bottom")
	)
	(footprint ""
		(layer "F.Cu")
		(at 452.628 -148.59 180)
		(property "Reference" "R25W164"
			(at -0.8382 -0.67818 180)
			(unlocked yes)
			(layer "F.SilkS")
			(effects
				(font
					(size 0.4064 0.254)
					(thickness 0.1524)
				)
				(justify left)
			)
		)
		(property "Value" ""
			(at 0 0 180)
			(layer "F.Fab")
			(effects
				(font
					(size 1.27 1.27)
				)
			)
		)
		(duplicate_pad_numbers_are_jumpers no)
		(fp_poly
			(pts
				(xy -0.2794 -0.1016) (xy 0.2794 -0.1016) (xy 0.2794 0.9906) (xy -0.2794 0.9906)
			)
			(stroke
				(width 0)
				(type default)
			)
			(fill no)
			(layer "F.CrtYd")
		)
		(fp_line
			(start 0.2794 0.9906)
			(end 0.2794 -0.1016)
			(stroke
				(width 0.1)
				(type default)
			)
			(layer "F.Fab")
		)
		(fp_line
			(start 0.2794 -0.1016)
			(end -0.2794 -0.1016)
			(stroke
				(width 0.1)
				(type default)
			)
			(layer "F.Fab")
		)
		(fp_line
			(start -0.2794 0.9906)
			(end 0.2794 0.9906)
			(stroke
				(width 0.1)
				(type default)
			)
			(layer "F.Fab")
		)
		(fp_line
			(start -0.2794 -0.1016)
			(end -0.2794 0.9906)
			(stroke
				(width 0.1)
				(type default)
			)
			(layer "F.Fab")
		)
		(pad "1" smd rect
			(at 0 0 180)
			(size 0.508 0.508)
			(layers "F.Cu" "F.Mask" "F.Paste")
			(net "P1V05_PCH_STBY")
		)
		(pad "2" smd rect
			(at 0 0.889 180)
			(size 0.508 0.508)
			(layers "F.Cu" "F.Mask" "F.Paste")
			(net "P0V7_GTL2014_VREF_6")
		)
		(zone
			(layer "F.Cu")
			(hatch none 0.5)
			(connect_pads
				(clearance 0)
			)
			(min_thickness 0.25)
			(keepout
				(tracks not_allowed)
				(vias allowed)
				(pads allowed)
				(copperpour not_allowed)
				(footprints allowed)
			)
			(placement
				(enabled no)
				(sheetname "")
			)
			(fill
				(thermal_gap 0.5)
				(thermal_bridge_width 0.5)
				(island_removal_mode 0)
			)
			(polygon
				(pts
					(xy 452.882 -149.225) (xy 452.374 -149.225) (xy 452.374 -148.844) (xy 452.882 -148.844)
				)
			)
		)
		(zone
			(layer "F.Cu")
			(hatch none 0.5)
			(connect_pads
				(clearance 0)
			)
			(min_thickness 0.25)
			(keepout
				(tracks allowed)
				(vias not_allowed)
				(pads allowed)
				(copperpour not_allowed)
				(footprints allowed)
			)
			(placement
				(enabled no)
				(sheetname "")
			)
			(fill
				(thermal_gap 0.5)
				(thermal_bridge_width 0.5)
				(island_removal_mode 0)
			)
			(polygon
				(pts
					(xy 452.882 -148.844) (xy 452.374 -148.844) (xy 452.374 -149.225) (xy 452.882 -149.225)
				)
			)
		)
	)
	(footprint ""
		(layer "F.Cu")
		(at 403.733 -22.098 180)
		(property "Reference" "R25W150"
			(at -0.8382 -0.67818 180)
			(unlocked yes)
			(layer "F.SilkS")
			(effects
				(font
					(size 0.4064 0.254)
					(thickness 0.1524)
				)
				(justify left)
			)
		)
		(property "Value" ""
			(at 0 0 180)
			(layer "F.Fab")
			(effects
				(font
					(size 1.27 1.27)
				)
			)
		)
		(duplicate_pad_numbers_are_jumpers no)
		(fp_poly
			(pts
				(xy -0.2794 -0.1016) (xy 0.2794 -0.1016) (xy 0.2794 0.9906) (xy -0.2794 0.9906)
			)
			(stroke
				(width 0)
				(type default)
			)
			(fill no)
			(layer "F.CrtYd")
		)
		(fp_line
			(start 0.2794 0.9906)
			(end 0.2794 -0.1016)
			(stroke
				(width 0.1)
				(type default)
			)
			(layer "F.Fab")
		)
		(fp_line
			(start 0.2794 -0.1016)
			(end -0.2794 -0.1016)
			(stroke
				(width 0.1)
				(type default)
			)
			(layer "F.Fab")
		)
		(fp_line
			(start -0.2794 0.9906)
			(end 0.2794 0.9906)
			(stroke
				(width 0.1)
				(type default)
			)
			(layer "F.Fab")
		)
		(fp_line
			(start -0.2794 -0.1016)
			(end -0.2794 0.9906)
			(stroke
				(width 0.1)
				(type default)
			)
			(layer "F.Fab")
		)
		(pad "1" smd rect
			(at 0 0 180)
			(size 0.508 0.508)
			(layers "F.Cu" "F.Mask" "F.Paste")
			(net "GND")
		)
		(pad "2" smd rect
			(at 0 0.889 180)
			(size 0.508 0.508)
			(layers "F.Cu" "F.Mask" "F.Paste")
			(net "RMII_BMC_PCH_SPRNGVLLE_TXD0_R")
		)
		(zone
			(layer "F.Cu")
			(hatch none 0.5)
			(connect_pads
				(clearance 0)
			)
			(min_thickness 0.25)
			(keepout
				(tracks not_allowed)
				(vias allowed)
				(pads allowed)
				(copperpour not_allowed)
				(footprints allowed)
			)
			(placement
				(enabled no)
				(sheetname "")
			)
			(fill
				(thermal_gap 0.5)
				(thermal_bridge_width 0.5)
				(island_removal_mode 0)
			)
			(polygon
				(pts
					(xy 403.987 -22.733) (xy 403.479 -22.733) (xy 403.479 -22.352) (xy 403.987 -22.352)
				)
			)
		)
		(zone
			(layer "F.Cu")
			(hatch none 0.5)
			(connect_pads
				(clearance 0)
			)
			(min_thickness 0.25)
			(keepout
				(tracks allowed)
				(vias not_allowed)
				(pads allowed)
				(copperpour not_allowed)
				(footprints allowed)
			)
			(placement
				(enabled no)
				(sheetname "")
			)
			(fill
				(thermal_gap 0.5)
				(thermal_bridge_width 0.5)
				(island_removal_mode 0)
			)
			(polygon
				(pts
					(xy 403.987 -22.352) (xy 403.479 -22.352) (xy 403.479 -22.733) (xy 403.987 -22.733)
				)
			)
		)
	)
	(footprint ""
		(layer "F.Cu")
		(at 404.158196 -58.694828)
		(property "Reference" "R8E18"
			(at 0 0 0)
			(layer "F.SilkS")
			(hide yes)
			(effects
				(font
					(size 1.27 1.27)
				)
			)
		)
		(property "Value" ""
			(at 0 0 0)
			(layer "F.Fab")
			(effects
				(font
					(size 1.27 1.27)
				)
			)
		)
		(duplicate_pad_numbers_are_jumpers no)
		(fp_poly
			(pts
				(xy -0.2794 -0.1016) (xy 0.2794 -0.1016) (xy 0.2794 0.9906) (xy -0.2794 0.9906)
			)
			(stroke
				(width 0)
				(type default)
			)
			(fill no)
			(layer "F.CrtYd")
		)
		(fp_line
			(start -0.2794 -0.1016)
			(end -0.2794 0.9906)
			(stroke
				(width 0.1)
				(type default)
			)
			(layer "F.Fab")
		)
		(fp_line
			(start -0.2794 0.9906)
			(end 0.2794 0.9906)
			(stroke
				(width 0.1)
				(type default)
			)
			(layer "F.Fab")
		)
		(fp_line
			(start 0.2794 -0.1016)
			(end -0.2794 -0.1016)
			(stroke
				(width 0.1)
				(type default)
			)
			(layer "F.Fab")
		)
		(fp_line
			(start 0.2794 0.9906)
			(end 0.2794 -0.1016)
			(stroke
				(width 0.1)
				(type default)
			)
			(layer "F.Fab")
		)
		(pad "1" smd rect
			(at 0 0)
			(size 0.508 0.508)
			(layers "F.Cu" "F.Mask" "F.Paste")
			(net "P5V_STBY")
		)
		(pad "2" smd rect
			(at 0 0.889)
			(size 0.508 0.508)
			(layers "F.Cu" "F.Mask" "F.Paste")
			(net "GND")
		)
		(zone
			(layer "F.Cu")
			(hatch none 0.5)
			(connect_pads
				(clearance 0)
			)
			(min_thickness 0.25)
			(keepout
				(tracks allowed)
				(vias not_allowed)
				(pads allowed)
				(copperpour not_allowed)
				(footprints allowed)
			)
			(placement
				(enabled no)
				(sheetname "")
			)
			(fill
				(thermal_gap 0.5)
				(thermal_bridge_width 0.5)
				(island_removal_mode 0)
			)
			(polygon
				(pts
					(xy 403.904196 -58.440828) (xy 404.412196 -58.440828) (xy 404.412196 -58.059828) (xy 403.904196 -58.059828)
				)
			)
		)
		(zone
			(layer "F.Cu")
			(hatch none 0.5)
			(connect_pads
				(clearance 0)
			)
			(min_thickness 0.25)
			(keepout
				(tracks not_allowed)
				(vias allowed)
				(pads allowed)
				(copperpour not_allowed)
				(footprints allowed)
			)
			(placement
				(enabled no)
				(sheetname "")
			)
			(fill
				(thermal_gap 0.5)
				(thermal_bridge_width 0.5)
				(island_removal_mode 0)
			)
			(polygon
				(pts
					(xy 403.904196 -58.059828) (xy 404.412196 -58.059828) (xy 404.412196 -58.440828) (xy 403.904196 -58.440828)
				)
			)
		)
	)
)
